(kicad_pcb
	(version 20260206)
	(generator "pcbnew")
	(generator_version "10.0")
	(general
		(thickness 1.6)
		(legacy_teardrops no)
	)
	(paper "A4")
	(title_block
		(title "01162023_DA0F0TEBIF0_F0T_Expander_BD_F_brd_V02_OCP.brd")
		(comment 1 "Grand Teton / footprints 4861-4866 of 9728")
	)
	(layers
		(0 "F.Cu" signal "TOP")
		(4 "In1.Cu" signal "GND")
		(6 "In2.Cu" signal "VCC")
		(8 "In3.Cu" signal "VCC1")
		(10 "In4.Cu" signal "GND1")
		(12 "In5.Cu" signal "IN1")
		(14 "In6.Cu" signal "GND2")
		(16 "In7.Cu" signal "IN2")
		(18 "In8.Cu" signal "GND3")
		(20 "In9.Cu" signal "IN3")
		(22 "In10.Cu" signal "GND4")
		(24 "In11.Cu" signal "IN4")
		(26 "In12.Cu" signal "GND5")
		(28 "In13.Cu" signal "IN5")
		(30 "In14.Cu" signal "GND6")
		(32 "In15.Cu" signal "IN6")
		(34 "In16.Cu" signal "GND7")
		(2 "B.Cu" signal "BOTTOM")
		(9 "F.Adhes" user "F.Adhesive")
		(11 "B.Adhes" user "B.Adhesive")
		(13 "F.Paste" user "Package Geometry/Pastemask Top")
		(15 "B.Paste" user "Package Geometry/Pastemask Bottom")
		(5 "F.SilkS" user "Ref Des/Silkscreen Top")
		(7 "B.SilkS" user "Ref Des/Silkscreen Bottom")
		(1 "F.Mask" user "Board Geometry/Soldermask Top")
		(3 "B.Mask" user "Board Geometry/Soldermask Bottom")
		(17 "Dwgs.User" user "User.Drawings")
		(19 "Cmts.User" user "User.Comments")
		(21 "Eco1.User" user "User.Eco1")
		(23 "Eco2.User" user "User.Eco2")
		(25 "Edge.Cuts" user "Board Geometry/Outline")
		(27 "Margin" user)
		(31 "F.CrtYd" user "Package Geometry/Place Bound Top")
		(29 "B.CrtYd" user "Package Geometry/Place Bound Bottom")
		(35 "F.Fab" user "Ref Des/Assembly Top")
		(33 "B.Fab" user "Ref Des/Assembly Bottom")
	)
	(footprint ""
		(layer "F.Cu")
		(at 78.243684 -45.88891)
		(property "Reference" "R532"
			(at 0 0 0)
			(layer "F.SilkS")
			(hide yes)
			(effects
				(font
					(size 1.27 1.27)
				)
			)
		)
		(property "Value" ""
			(at 0 0 0)
			(layer "F.Fab")
			(effects
				(font
					(size 1.27 1.27)
				)
			)
		)
		(duplicate_pad_numbers_are_jumpers no)
		(fp_line
			(start -0.7874 -0.4064)
			(end 0.7874 -0.4064)
			(stroke
				(width 0.1524)
				(type default)
			)
			(layer "F.SilkS")
		)
		(fp_line
			(start -0.7874 0.4064)
			(end -0.7874 -0.4064)
			(stroke
				(width 0.1524)
				(type default)
			)
			(layer "F.SilkS")
		)
		(fp_line
			(start 0.7874 -0.4064)
			(end 0.7874 0.4064)
			(stroke
				(width 0.1524)
				(type default)
			)
			(layer "F.SilkS")
		)
		(fp_line
			(start 0.7874 0.4064)
			(end -0.7874 0.4064)
			(stroke
				(width 0.1524)
				(type default)
			)
			(layer "F.SilkS")
		)
		(fp_line
			(start -0.67945 -0.305054)
			(end -0.12065 -0.305054)
			(stroke
				(width 0.1)
				(type default)
			)
			(layer "F.Fab")
		)
		(fp_line
			(start -0.67945 0.3048)
			(end -0.67945 -0.305054)
			(stroke
				(width 0.1)
				(type default)
			)
			(layer "F.Fab")
		)
		(fp_line
			(start -0.12065 -0.305054)
			(end -0.12065 -0.2794)
			(stroke
				(width 0.1)
				(type default)
			)
			(layer "F.Fab")
		)
		(fp_line
			(start -0.12065 -0.2794)
			(end 0.12065 -0.2794)
			(stroke
				(width 0.1)
				(type default)
			)
			(layer "F.Fab")
		)
		(fp_line
			(start -0.12065 0.2794)
			(end -0.12065 0.3048)
			(stroke
				(width 0.1)
				(type default)
			)
			(layer "F.Fab")
		)
		(fp_line
			(start -0.12065 0.3048)
			(end -0.67945 0.3048)
			(stroke
				(width 0.1)
				(type default)
			)
			(layer "F.Fab")
		)
		(fp_line
			(start 0.120396 0.2794)
			(end -0.12065 0.2794)
			(stroke
				(width 0.1)
				(type default)
			)
			(layer "F.Fab")
		)
		(fp_line
			(start 0.120396 0.3048)
			(end 0.120396 0.2794)
			(stroke
				(width 0.1)
				(type default)
			)
			(layer "F.Fab")
		)
		(fp_line
			(start 0.12065 -0.3048)
			(end 0.67945 -0.3048)
			(stroke
				(width 0.1)
				(type default)
			)
			(layer "F.Fab")
		)
		(fp_line
			(start 0.12065 -0.2794)
			(end 0.12065 -0.3048)
			(stroke
				(width 0.1)
				(type default)
			)
			(layer "F.Fab")
		)
		(fp_line
			(start 0.67945 -0.3048)
			(end 0.67945 0.3048)
			(stroke
				(width 0.1)
				(type default)
			)
			(layer "F.Fab")
		)
		(fp_line
			(start 0.67945 0.3048)
			(end 0.120396 0.3048)
			(stroke
				(width 0.1)
				(type default)
			)
			(layer "F.Fab")
		)
		(pad "1" smd circle
			(at -0.40005 0)
			(size 0 0)
			(layers "F.Cu" "F.Mask" "F.Paste")
			(net "SSD2_ADC_A0")
		)
		(pad "2" smd circle
			(at 0.40005 0)
			(size 0 0)
			(layers "F.Cu" "F.Mask" "F.Paste")
			(net "GND")
		)
	)
	(footprint ""
		(layer "F.Cu")
		(at 359.85831 -257.115564)
		(property "Reference" "PR132"
			(at 0 0 0)
			(layer "F.SilkS")
			(hide yes)
			(effects
				(font
					(size 1.27 1.27)
				)
			)
		)
		(property "Value" ""
			(at 0 0 0)
			(layer "F.Fab")
			(effects
				(font
					(size 1.27 1.27)
				)
			)
		)
		(duplicate_pad_numbers_are_jumpers no)
		(fp_line
			(start -0.7874 -0.4064)
			(end 0.7874 -0.4064)
			(stroke
				(width 0.1524)
				(type default)
			)
			(layer "F.SilkS")
		)
		(fp_line
			(start -0.7874 0.4064)
			(end -0.7874 -0.4064)
			(stroke
				(width 0.1524)
				(type default)
			)
			(layer "F.SilkS")
		)
		(fp_line
			(start 0.7874 -0.4064)
			(end 0.7874 0.4064)
			(stroke
				(width 0.1524)
				(type default)
			)
			(layer "F.SilkS")
		)
		(fp_line
			(start 0.7874 0.4064)
			(end -0.7874 0.4064)
			(stroke
				(width 0.1524)
				(type default)
			)
			(layer "F.SilkS")
		)
		(fp_line
			(start -0.67945 -0.305054)
			(end -0.12065 -0.305054)
			(stroke
				(width 0.1)
				(type default)
			)
			(layer "F.Fab")
		)
		(fp_line
			(start -0.67945 0.3048)
			(end -0.67945 -0.305054)
			(stroke
				(width 0.1)
				(type default)
			)
			(layer "F.Fab")
		)
		(fp_line
			(start -0.12065 -0.305054)
			(end -0.12065 -0.2794)
			(stroke
				(width 0.1)
				(type default)
			)
			(layer "F.Fab")
		)
		(fp_line
			(start -0.12065 -0.2794)
			(end 0.12065 -0.2794)
			(stroke
				(width 0.1)
				(type default)
			)
			(layer "F.Fab")
		)
		(fp_line
			(start -0.12065 0.2794)
			(end -0.12065 0.3048)
			(stroke
				(width 0.1)
				(type default)
			)
			(layer "F.Fab")
		)
		(fp_line
			(start -0.12065 0.3048)
			(end -0.67945 0.3048)
			(stroke
				(width 0.1)
				(type default)
			)
			(layer "F.Fab")
		)
		(fp_line
			(start 0.120396 0.2794)
			(end -0.12065 0.2794)
			(stroke
				(width 0.1)
				(type default)
			)
			(layer "F.Fab")
		)
		(fp_line
			(start 0.120396 0.3048)
			(end 0.120396 0.2794)
			(stroke
				(width 0.1)
				(type default)
			)
			(layer "F.Fab")
		)
		(fp_line
			(start 0.12065 -0.3048)
			(end 0.67945 -0.3048)
			(stroke
				(width 0.1)
				(type default)
			)
			(layer "F.Fab")
		)
		(fp_line
			(start 0.12065 -0.2794)
			(end 0.12065 -0.3048)
			(stroke
				(width 0.1)
				(type default)
			)
			(layer "F.Fab")
		)
		(fp_line
			(start 0.67945 -0.3048)
			(end 0.67945 0.3048)
			(stroke
				(width 0.1)
				(type default)
			)
			(layer "F.Fab")
		)
		(fp_line
			(start 0.67945 0.3048)
			(end 0.120396 0.3048)
			(stroke
				(width 0.1)
				(type default)
			)
			(layer "F.Fab")
		)
		(pad "1" smd circle
			(at -0.40005 0)
			(size 0 0)
			(layers "F.Cu" "F.Mask" "F.Paste")
			(net "P0V8_PEX2_PINALRT")
		)
		(pad "2" smd circle
			(at 0.40005 0)
			(size 0 0)
			(layers "F.Cu" "F.Mask" "F.Paste")
			(net "P3V3_AUX")
		)
	)
	(footprint ""
		(layer "F.Cu")
		(at 155.380436 -135.815324)
		(property "Reference" "C244"
			(at 0 0 0)
			(layer "F.SilkS")
			(hide yes)
			(effects
				(font
					(size 1.27 1.27)
				)
			)
		)
		(property "Value" ""
			(at 0 0 0)
			(layer "F.Fab")
			(effects
				(font
					(size 1.27 1.27)
				)
			)
		)
		(duplicate_pad_numbers_are_jumpers no)
		(fp_line
			(start -0.299974 -0.150114)
			(end 0.299974 -0.150114)
			(stroke
				(width 0.1)
				(type default)
			)
			(layer "F.Fab")
		)
		(fp_line
			(start -0.299974 0.150114)
			(end -0.299974 -0.150114)
			(stroke
				(width 0.1)
				(type default)
			)
			(layer "F.Fab")
		)
		(fp_line
			(start 0.299974 -0.150114)
			(end 0.299974 0.150114)
			(stroke
				(width 0.1)
				(type default)
			)
			(layer "F.Fab")
		)
		(fp_line
			(start 0.299974 0.150114)
			(end -0.299974 0.150114)
			(stroke
				(width 0.1)
				(type default)
			)
			(layer "F.Fab")
		)
		(pad "1" smd rect
			(at -0.2667 0)
			(size 0.3048 0.381)
			(layers "F.Cu" "F.Mask" "F.Paste")
			(net "P5E_PEX1_STN1_TX_DN<31>")
		)
		(pad "2" smd rect
			(at 0.2667 0)
			(size 0.3048 0.381)
			(layers "F.Cu" "F.Mask" "F.Paste")
			(net "P5E_PEX1_STN1_TX_C_DN<31>")
		)
	)
	(footprint ""
		(layer "F.Cu")
		(at 257.169412 -349.695008 180)
		(property "Reference" "R6654"
			(at 0 0 180)
			(layer "F.SilkS")
			(hide yes)
			(effects
				(font
					(size 1.27 1.27)
				)
			)
		)
		(property "Value" ""
			(at 0 0 180)
			(layer "F.Fab")
			(effects
				(font
					(size 1.27 1.27)
				)
			)
		)
		(duplicate_pad_numbers_are_jumpers no)
		(fp_line
			(start 0.7874 0.4064)
			(end -0.7874 0.4064)
			(stroke
				(width 0.1524)
				(type default)
			)
			(layer "F.SilkS")
		)
		(fp_line
			(start 0.7874 -0.4064)
			(end 0.7874 0.4064)
			(stroke
				(width 0.1524)
				(type default)
			)
			(layer "F.SilkS")
		)
		(fp_line
			(start -0.7874 0.4064)
			(end -0.7874 -0.4064)
			(stroke
				(width 0.1524)
				(type default)
			)
			(layer "F.SilkS")
		)
		(fp_line
			(start -0.7874 -0.4064)
			(end 0.7874 -0.4064)
			(stroke
				(width 0.1524)
				(type default)
			)
			(layer "F.SilkS")
		)
		(fp_line
			(start 0.67945 0.3048)
			(end 0.120396 0.3048)
			(stroke
				(width 0.1)
				(type default)
			)
			(layer "F.Fab")
		)
		(fp_line
			(start 0.67945 -0.3048)
			(end 0.67945 0.3048)
			(stroke
				(width 0.1)
				(type default)
			)
			(layer "F.Fab")
		)
		(fp_line
			(start 0.12065 -0.2794)
			(end 0.12065 -0.3048)
			(stroke
				(width 0.1)
				(type default)
			)
			(layer "F.Fab")
		)
		(fp_line
			(start 0.12065 -0.3048)
			(end 0.67945 -0.3048)
			(stroke
				(width 0.1)
				(type default)
			)
			(layer "F.Fab")
		)
		(fp_line
			(start 0.120396 0.3048)
			(end 0.120396 0.2794)
			(stroke
				(width 0.1)
				(type default)
			)
			(layer "F.Fab")
		)
		(fp_line
			(start 0.120396 0.2794)
			(end -0.12065 0.2794)
			(stroke
				(width 0.1)
				(type default)
			)
			(layer "F.Fab")
		)
		(fp_line
			(start -0.12065 0.3048)
			(end -0.67945 0.3048)
			(stroke
				(width 0.1)
				(type default)
			)
			(layer "F.Fab")
		)
		(fp_line
			(start -0.12065 0.2794)
			(end -0.12065 0.3048)
			(stroke
				(width 0.1)
				(type default)
			)
			(layer "F.Fab")
		)
		(fp_line
			(start -0.12065 -0.2794)
			(end 0.12065 -0.2794)
			(stroke
				(width 0.1)
				(type default)
			)
			(layer "F.Fab")
		)
		(fp_line
			(start -0.12065 -0.305054)
			(end -0.12065 -0.2794)
			(stroke
				(width 0.1)
				(type default)
			)
			(layer "F.Fab")
		)
		(fp_line
			(start -0.67945 0.3048)
			(end -0.67945 -0.305054)
			(stroke
				(width 0.1)
				(type default)
			)
			(layer "F.Fab")
		)
		(fp_line
			(start -0.67945 -0.305054)
			(end -0.12065 -0.305054)
			(stroke
				(width 0.1)
				(type default)
			)
			(layer "F.Fab")
		)
		(pad "1" smd circle
			(at -0.40005 0 180)
			(size 0 0)
			(layers "F.Cu" "F.Mask" "F.Paste")
			(net "A_HSC_LOW_GATE")
		)
		(pad "2" smd circle
			(at 0.40005 0 180)
			(size 0 0)
			(layers "F.Cu" "F.Mask" "F.Paste")
			(net "GND")
		)
	)
	(footprint ""
		(layer "F.Cu")
		(at 224.82683 -296.764202 -90)
		(property "Reference" "PL20"
			(at -3.59664 -7.405624 90)
			(unlocked yes)
			(layer "F.SilkS")
			(effects
				(font
					(size 0.7874 0.5842)
					(thickness 0.1524)
				)
				(justify left)
			)
		)
		(property "Value" ""
			(at 0 0 270)
			(layer "F.Fab")
			(effects
				(font
					(size 1.27 1.27)
				)
			)
		)
		(duplicate_pad_numbers_are_jumpers no)
		(fp_line
			(start -6.849872 6.450076)
			(end -6.849872 1.9812)
			(stroke
				(width 0.1524)
				(type default)
			)
			(layer "F.SilkS")
		)
		(fp_line
			(start 6.849872 6.450076)
			(end -6.849872 6.450076)
			(stroke
				(width 0.1524)
				(type default)
			)
			(layer "F.SilkS")
		)
		(fp_line
			(start 6.849872 1.9812)
			(end 6.849872 6.450076)
			(stroke
				(width 0.1524)
				(type default)
			)
			(layer "F.SilkS")
		)
		(fp_line
			(start -6.849872 -1.9812)
			(end -6.849872 -6.450076)
			(stroke
				(width 0.1524)
				(type default)
			)
			(layer "F.SilkS")
		)
		(fp_line
			(start -6.849872 -6.450076)
			(end 6.849872 -6.450076)
			(stroke
				(width 0.1524)
				(type default)
			)
			(layer "F.SilkS")
		)
		(fp_line
			(start 6.849872 -6.450076)
			(end 6.849872 -1.9812)
			(stroke
				(width 0.1524)
				(type default)
			)
			(layer "F.SilkS")
		)
		(fp_line
			(start -6.849872 6.450076)
			(end -6.849872 -6.450076)
			(stroke
				(width 0.1)
				(type default)
			)
			(layer "F.Fab")
		)
		(fp_line
			(start 6.849872 6.450076)
			(end -6.849872 6.450076)
			(stroke
				(width 0.1)
				(type default)
			)
			(layer "F.Fab")
		)
		(fp_line
			(start -6.849872 -6.450076)
			(end 6.849872 -6.450076)
			(stroke
				(width 0.1)
				(type default)
			)
			(layer "F.Fab")
		)
		(fp_line
			(start 6.849872 -6.450076)
			(end 6.849872 6.450076)
			(stroke
				(width 0.1)
				(type default)
			)
			(layer "F.Fab")
		)
		(pad "1" smd rect
			(at -5.407406 0 270)
			(size 2.9464 3.7084)
			(layers "F.Cu" "F.Mask" "F.Paste")
			(net "SW_P1V25_PEX1_PH")
		)
		(pad "2" smd rect
			(at 5.407406 0 270)
			(size 2.9464 3.7084)
			(layers "F.Cu" "F.Mask" "F.Paste")
			(net "P1V25_PEX1_R")
		)
	)
	(footprint ""
		(layer "F.Cu")
		(at 250.94946 -195.573396 90)
		(property "Reference" "R5645"
			(at 0 0 90)
			(layer "F.SilkS")
			(hide yes)
			(effects
				(font
					(size 1.27 1.27)
				)
			)
		)
		(property "Value" ""
			(at 0 0 90)
			(layer "F.Fab")
			(effects
				(font
					(size 1.27 1.27)
				)
			)
		)
		(duplicate_pad_numbers_are_jumpers no)
		(fp_line
			(start 0.7874 -0.4064)
			(end 0.7874 0.4064)
			(stroke
				(width 0.1524)
				(type default)
			)
			(layer "F.SilkS")
		)
		(fp_line
			(start -0.7874 -0.4064)
			(end 0.7874 -0.4064)
			(stroke
				(width 0.1524)
				(type default)
			)
			(layer "F.SilkS")
		)
		(fp_line
			(start 0.7874 0.4064)
			(end -0.7874 0.4064)
			(stroke
				(width 0.1524)
				(type default)
			)
			(layer "F.SilkS")
		)
		(fp_line
			(start -0.7874 0.4064)
			(end -0.7874 -0.4064)
			(stroke
				(width 0.1524)
				(type default)
			)
			(layer "F.SilkS")
		)
		(fp_line
			(start -0.12065 -0.305054)
			(end -0.12065 -0.2794)
			(stroke
				(width 0.1)
				(type default)
			)
			(layer "F.Fab")
		)
		(fp_line
			(start -0.67945 -0.305054)
			(end -0.12065 -0.305054)
			(stroke
				(width 0.1)
				(type default)
			)
			(layer "F.Fab")
		)
		(fp_line
			(start 0.67945 -0.3048)
			(end 0.67945 0.3048)
			(stroke
				(width 0.1)
				(type default)
			)
			(layer "F.Fab")
		)
		(fp_line
			(start 0.12065 -0.3048)
			(end 0.67945 -0.3048)
			(stroke
				(width 0.1)
				(type default)
			)
			(layer "F.Fab")
		)
		(fp_line
			(start 0.12065 -0.2794)
			(end 0.12065 -0.3048)
			(stroke
				(width 0.1)
				(type default)
			)
			(layer "F.Fab")
		)
		(fp_line
			(start -0.12065 -0.2794)
			(end 0.12065 -0.2794)
			(stroke
				(width 0.1)
				(type default)
			)
			(layer "F.Fab")
		)
		(fp_line
			(start 0.120396 0.2794)
			(end -0.12065 0.2794)
			(stroke
				(width 0.1)
				(type default)
			)
			(layer "F.Fab")
		)
		(fp_line
			(start -0.12065 0.2794)
			(end -0.12065 0.3048)
			(stroke
				(width 0.1)
				(type default)
			)
			(layer "F.Fab")
		)
		(fp_line
			(start 0.67945 0.3048)
			(end 0.120396 0.3048)
			(stroke
				(width 0.1)
				(type default)
			)
			(layer "F.Fab")
		)
		(fp_line
			(start 0.120396 0.3048)
			(end 0.120396 0.2794)
			(stroke
				(width 0.1)
				(type default)
			)
			(layer "F.Fab")
		)
		(fp_line
			(start -0.12065 0.3048)
			(end -0.67945 0.3048)
			(stroke
				(width 0.1)
				(type default)
			)
			(layer "F.Fab")
		)
		(fp_line
			(start -0.67945 0.3048)
			(end -0.67945 -0.305054)
			(stroke
				(width 0.1)
				(type default)
			)
			(layer "F.Fab")
		)
		(pad "1" smd circle
			(at -0.40005 0 90)
			(size 0 0)
			(layers "F.Cu" "F.Mask" "F.Paste")
			(net "JTAG_BIC_TCK_R")
		)
		(pad "2" smd circle
			(at 0.40005 0 90)
			(size 0 0)
			(layers "F.Cu" "F.Mask" "F.Paste")
			(net "JTAG_BIC_TCK_R1")
		)
	)
)
